# T6G (Grand Teton) — schematic netlist excerpt (pin names and nets, part order shuffled) for the footprints in the layout excerpt that follows; sources: Cadence DE-HDL packaged netlist, KiCad conversion of 04192023_DAF0TMB3IC0_F0TG_MB_C_brd_V02_OCP.brd

R1411  Q_RES  1K 1% CHIP  pkg 0201LF  page 185 : A = P1V8_CPU0_RT_1D ; B = SMB_RT_CPU0_P0_ROM_MUX_1D_SCL
PR88  Q_RES  2.2 1% CHIP  pkg 0402LF  page 202 : A = PVDDCR_CPU1_P0_PVCC ; B = PVDDCR_CPU1_P0_VCC3
PC6815  Q_CAPP  470UF 2.5V 20% SPCAP  pkg SMLF  page 365 : A = P0V9_CPU1_RT_2D ; B = GND

(kicad_pcb
	(version 20260206)
	(generator "pcbnew")
	(generator_version "10.0")
	(general
		(thickness 1.6)
		(legacy_teardrops no)
	)
	(paper "A4")
	(title_block
		(title "04192023_DAF0TMB3IC0_F0TG_MB_C_brd_V02_OCP.brd")
		(comment 1 "Grand Teton / footprints 6908-6910 of 8354")
	)
	(layers
		(0 "F.Cu" signal "TOP")
		(4 "In1.Cu" signal "GND")
		(6 "In2.Cu" signal "IN1")
		(8 "In3.Cu" signal "GND1")
		(10 "In4.Cu" signal "IN2")
		(12 "In5.Cu" signal "GND2")
		(14 "In6.Cu" signal "IN3")
		(16 "In7.Cu" signal "GND3")
		(18 "In8.Cu" signal "VCC")
		(20 "In9.Cu" signal "VCC1")
		(22 "In10.Cu" signal "GND4")
		(24 "In11.Cu" signal "IN4")
		(26 "In12.Cu" signal "GND5")
		(28 "In13.Cu" signal "IN5")
		(30 "In14.Cu" signal "GND6")
		(32 "In15.Cu" signal "IN6")
		(34 "In16.Cu" signal "GND7")
		(2 "B.Cu" signal "BOTTOM")
		(9 "F.Adhes" user "F.Adhesive")
		(11 "B.Adhes" user "B.Adhesive")
		(13 "F.Paste" user "Package Geometry/Pastemask Top")
		(15 "B.Paste" user "Package Geometry/Pastemask Bottom")
		(5 "F.SilkS" user "Ref Des/Silkscreen Top")
		(7 "B.SilkS" user "Ref Des/Silkscreen Bottom")
		(1 "F.Mask" user "Board Geometry/Soldermask Top")
		(3 "B.Mask" user "Board Geometry/Soldermask Bottom")
		(17 "Dwgs.User" user "User.Drawings")
		(19 "Cmts.User" user "User.Comments")
		(21 "Eco1.User" user "User.Eco1")
		(23 "Eco2.User" user "User.Eco2")
		(25 "Edge.Cuts" user "Board Geometry/Outline")
		(27 "Margin" user)
		(31 "F.CrtYd" user "Package Geometry/Place Bound Top")
		(29 "B.CrtYd" user "Package Geometry/Place Bound Bottom")
		(35 "F.Fab" user "Ref Des/Assembly Top")
		(33 "B.Fab" user "Ref Des/Assembly Bottom")
	)
	(footprint ""
		(layer "B.Cu")
		(at 23.235158 -383.53873 -90)
		(property "Reference" "PC6815"
			(at 1.64973 -4.043172 270)
			(unlocked yes)
			(layer "B.SilkS")
			(effects
				(font
					(size 0.7874 0.5842)
					(thickness 0.1524)
				)
				(justify left mirror)
			)
		)
		(property "Value" ""
			(at 0 0 90)
			(layer "B.Fab")
			(effects
				(font
					(size 1.27 1.27)
				)
				(justify mirror)
			)
		)
		(duplicate_pad_numbers_are_jumpers no)
		(fp_line
			(start 4.83108 2.150364)
			(end 4.447794 2.149348)
			(stroke
				(width 0.1524)
				(type default)
			)
			(layer "B.SilkS")
		)
		(fp_line
			(start -4.53898 2.15011)
			(end 4.53898 2.15011)
			(stroke
				(width 0.1524)
				(type default)
			)
			(layer "B.SilkS")
		)
		(fp_line
			(start 4.53898 2.15011)
			(end 4.53898 -2.15011)
			(stroke
				(width 0.1524)
				(type default)
			)
			(layer "B.SilkS")
		)
		(fp_line
			(start -4.53898 -2.15011)
			(end -4.53898 2.15011)
			(stroke
				(width 0.1524)
				(type default)
			)
			(layer "B.SilkS")
		)
		(fp_line
			(start 4.53898 -2.15011)
			(end -4.53898 -2.15011)
			(stroke
				(width 0.1524)
				(type default)
			)
			(layer "B.SilkS")
		)
		(fp_line
			(start 4.53898 -2.150618)
			(end 4.539742 2.152142)
			(stroke
				(width 0.1524)
				(type default)
			)
			(layer "B.SilkS")
		)
		(fp_line
			(start 4.69138 -2.150618)
			(end 4.692396 2.161032)
			(stroke
				(width 0.1524)
				(type default)
			)
			(layer "B.SilkS")
		)
		(fp_line
			(start 4.84378 -2.150618)
			(end 4.842256 2.163064)
			(stroke
				(width 0.1524)
				(type default)
			)
			(layer "B.SilkS")
		)
		(fp_line
			(start 4.84378 -2.150618)
			(end 4.53898 -2.150618)
			(stroke
				(width 0.1524)
				(type default)
			)
			(layer "B.SilkS")
		)
		(fp_line
			(start -3.64998 2.15011)
			(end 3.64998 2.15011)
			(stroke
				(width 0.1)
				(type default)
			)
			(layer "B.Fab")
		)
		(fp_line
			(start 3.64998 2.15011)
			(end 3.64998 -2.15011)
			(stroke
				(width 0.1)
				(type default)
			)
			(layer "B.Fab")
		)
		(fp_line
			(start -3.64998 -2.15011)
			(end -3.64998 2.15011)
			(stroke
				(width 0.1)
				(type default)
			)
			(layer "B.Fab")
		)
		(fp_line
			(start 3.64998 -2.15011)
			(end -3.64998 -2.15011)
			(stroke
				(width 0.1)
				(type default)
			)
			(layer "B.Fab")
		)
		(fp_text user "+"
			(at 6.87451 1.371854 270)
			(unlocked yes)
			(layer "B.SilkS")
			(effects
				(font
					(size 1.905 1.4224)
					(thickness 0.1524)
				)
				(justify left mirror)
			)
		)
		(fp_text user "-"
			(at -4.313174 -0.094488 270)
			(unlocked yes)
			(layer "B.SilkS")
			(effects
				(font
					(size 1.905 1.4224)
					(thickness 0.1524)
				)
				(justify left mirror)
			)
		)
		(fp_text user "-"
			(at -4.313174 -0.094488 270)
			(unlocked yes)
			(layer "B.Fab")
			(effects
				(font
					(size 1.905 1.4224)
					(thickness 0.1524)
				)
				(justify left mirror)
			)
		)
		(fp_text user "+"
			(at 6.214872 -0.337058 270)
			(unlocked yes)
			(layer "B.Fab")
			(effects
				(font
					(size 1.905 1.4224)
					(thickness 0.1524)
				)
				(justify left mirror)
			)
		)
		(pad "1" smd rect
			(at 3.199892 0 90)
			(size 2.413 2.8194)
			(layers "B.Cu" "B.Mask" "B.Paste")
			(net "P0V9_CPU1_RT_2D")
		)
		(pad "2" smd rect
			(at -3.199892 0 90)
			(size 2.413 2.8194)
			(layers "B.Cu" "B.Mask" "B.Paste")
			(net "GND")
		)
	)
	(footprint ""
		(layer "B.Cu")
		(at 316.034928 -336.054446 -90)
		(property "Reference" "PR88"
			(at 0 0 90)
			(layer "B.SilkS")
			(hide yes)
			(effects
				(font
					(size 1.27 1.27)
				)
				(justify mirror)
			)
		)
		(property "Value" ""
			(at 0 0 90)
			(layer "B.Fab")
			(effects
				(font
					(size 1.27 1.27)
				)
				(justify mirror)
			)
		)
		(duplicate_pad_numbers_are_jumpers no)
		(fp_line
			(start -0.7874 0.4064)
			(end 0.7874 0.4064)
			(stroke
				(width 0.1524)
				(type default)
			)
			(layer "B.SilkS")
		)
		(fp_line
			(start 0.7874 0.4064)
			(end 0.7874 -0.4064)
			(stroke
				(width 0.1524)
				(type default)
			)
			(layer "B.SilkS")
		)
		(fp_line
			(start -0.7874 -0.4064)
			(end -0.7874 0.4064)
			(stroke
				(width 0.1524)
				(type default)
			)
			(layer "B.SilkS")
		)
		(fp_line
			(start 0.7874 -0.4064)
			(end -0.7874 -0.4064)
			(stroke
				(width 0.1524)
				(type default)
			)
			(layer "B.SilkS")
		)
		(fp_line
			(start -0.67945 0.3048)
			(end -0.120396 0.3048)
			(stroke
				(width 0.1)
				(type default)
			)
			(layer "B.Fab")
		)
		(fp_line
			(start -0.120396 0.3048)
			(end -0.120396 0.2794)
			(stroke
				(width 0.1)
				(type default)
			)
			(layer "B.Fab")
		)
		(fp_line
			(start 0.12065 0.3048)
			(end 0.67945 0.3048)
			(stroke
				(width 0.1)
				(type default)
			)
			(layer "B.Fab")
		)
		(fp_line
			(start 0.67945 0.3048)
			(end 0.67945 -0.305054)
			(stroke
				(width 0.1)
				(type default)
			)
			(layer "B.Fab")
		)
		(fp_line
			(start -0.120396 0.2794)
			(end 0.12065 0.2794)
			(stroke
				(width 0.1)
				(type default)
			)
			(layer "B.Fab")
		)
		(fp_line
			(start 0.12065 0.2794)
			(end 0.12065 0.3048)
			(stroke
				(width 0.1)
				(type default)
			)
			(layer "B.Fab")
		)
		(fp_line
			(start -0.12065 -0.2794)
			(end -0.12065 -0.3048)
			(stroke
				(width 0.1)
				(type default)
			)
			(layer "B.Fab")
		)
		(fp_line
			(start 0.12065 -0.2794)
			(end -0.12065 -0.2794)
			(stroke
				(width 0.1)
				(type default)
			)
			(layer "B.Fab")
		)
		(fp_line
			(start -0.67945 -0.3048)
			(end -0.67945 0.3048)
			(stroke
				(width 0.1)
				(type default)
			)
			(layer "B.Fab")
		)
		(fp_line
			(start -0.12065 -0.3048)
			(end -0.67945 -0.3048)
			(stroke
				(width 0.1)
				(type default)
			)
			(layer "B.Fab")
		)
		(fp_line
			(start 0.12065 -0.305054)
			(end 0.12065 -0.2794)
			(stroke
				(width 0.1)
				(type default)
			)
			(layer "B.Fab")
		)
		(fp_line
			(start 0.67945 -0.305054)
			(end 0.12065 -0.305054)
			(stroke
				(width 0.1)
				(type default)
			)
			(layer "B.Fab")
		)
		(pad "1" smd circle
			(at 0.40005 0 90)
			(size 0 0)
			(layers "B.Cu" "B.Mask" "B.Paste")
			(net "PVDDCR_CPU1_P0_PVCC")
		)
		(pad "2" smd circle
			(at -0.40005 0 90)
			(size 0 0)
			(layers "B.Cu" "B.Mask" "B.Paste")
			(net "PVDDCR_CPU1_P0_VCC3")
		)
	)
	(footprint ""
		(layer "B.Cu")
		(at 301.082202 -427.668436 90)
		(property "Reference" "R1411"
			(at 0 0 90)
			(layer "B.SilkS")
			(hide yes)
			(effects
				(font
					(size 1.27 1.27)
				)
				(justify mirror)
			)
		)
		(property "Value" ""
			(at 0 0 90)
			(layer "B.Fab")
			(effects
				(font
					(size 1.27 1.27)
				)
				(justify mirror)
			)
		)
		(duplicate_pad_numbers_are_jumpers no)
		(fp_line
			(start 0.32512 -0.175006)
			(end -0.32512 -0.175006)
			(stroke
				(width 0.1)
				(type default)
			)
			(layer "B.Fab")
		)
		(fp_line
			(start -0.32512 -0.175006)
			(end -0.32512 0.175006)
			(stroke
				(width 0.1)
				(type default)
			)
			(layer "B.Fab")
		)
		(fp_line
			(start 0.32512 0.175006)
			(end 0.32512 -0.175006)
			(stroke
				(width 0.1)
				(type default)
			)
			(layer "B.Fab")
		)
		(fp_line
			(start -0.32512 0.175006)
			(end 0.32512 0.175006)
			(stroke
				(width 0.1)
				(type default)
			)
			(layer "B.Fab")
		)
		(pad "1" smd rect
			(at 0.2667 0 270)
			(size 0.3048 0.381)
			(layers "B.Cu" "B.Mask" "B.Paste")
			(net "P1V8_CPU0_RT_1D")
		)
		(pad "2" smd rect
			(at -0.2667 0 90)
			(size 0.3048 0.381)
			(layers "B.Cu" "B.Mask" "B.Paste")
			(net "SMB_RT_CPU0_P0_ROM_MUX_1D_SCL")
		)
	)
)
